# T6G (Grand Teton) — schematic netlist excerpt (pin names and nets, part order shuffled) for the footprints in the layout excerpt that follows; sources: Cadence DE-HDL packaged netlist, KiCad conversion of 04192023_DAF0TMB3IC0_F0TG_MB_C_brd_V02_OCP.brd

PC101  Q_CAPP  270UF 16V 20% OSCON  pkg THLF  page 201 : A = SW_P12V_AUX_PVDDCR_CPU1_P0_FLT ; B = GND
PC6573  Q_CAPP  390UF 2.5V 20% ALUM  pkg SMLF  page 363 : A = P0V9_CPU0_RT_2D ; B = GND
R3907  Q_RES  33K 1% CHIP  pkg 0402LF  page 268 : A = PDB_PRSNT_R_N ; B = GND

(kicad_pcb
	(version 20260206)
	(generator "pcbnew")
	(generator_version "10.0")
	(general
		(thickness 1.6)
		(legacy_teardrops no)
	)
	(paper "A4")
	(title_block
		(title "04192023_DAF0TMB3IC0_F0TG_MB_C_brd_V02_OCP.brd")
		(comment 1 "Grand Teton / footprints 4-6 of 8354")
	)
	(layers
		(0 "F.Cu" signal "TOP")
		(4 "In1.Cu" signal "GND")
		(6 "In2.Cu" signal "IN1")
		(8 "In3.Cu" signal "GND1")
		(10 "In4.Cu" signal "IN2")
		(12 "In5.Cu" signal "GND2")
		(14 "In6.Cu" signal "IN3")
		(16 "In7.Cu" signal "GND3")
		(18 "In8.Cu" signal "VCC")
		(20 "In9.Cu" signal "VCC1")
		(22 "In10.Cu" signal "GND4")
		(24 "In11.Cu" signal "IN4")
		(26 "In12.Cu" signal "GND5")
		(28 "In13.Cu" signal "IN5")
		(30 "In14.Cu" signal "GND6")
		(32 "In15.Cu" signal "IN6")
		(34 "In16.Cu" signal "GND7")
		(2 "B.Cu" signal "BOTTOM")
		(9 "F.Adhes" user "F.Adhesive")
		(11 "B.Adhes" user "B.Adhesive")
		(13 "F.Paste" user "Package Geometry/Pastemask Top")
		(15 "B.Paste" user "Package Geometry/Pastemask Bottom")
		(5 "F.SilkS" user "Ref Des/Silkscreen Top")
		(7 "B.SilkS" user "Ref Des/Silkscreen Bottom")
		(1 "F.Mask" user "Board Geometry/Soldermask Top")
		(3 "B.Mask" user "Board Geometry/Soldermask Bottom")
		(17 "Dwgs.User" user "User.Drawings")
		(19 "Cmts.User" user "User.Comments")
		(21 "Eco1.User" user "User.Eco1")
		(23 "Eco2.User" user "User.Eco2")
		(25 "Edge.Cuts" user "Board Geometry/Outline")
		(27 "Margin" user)
		(31 "F.CrtYd" user "Package Geometry/Place Bound Top")
		(29 "B.CrtYd" user "Package Geometry/Place Bound Bottom")
		(35 "F.Fab" user "Ref Des/Assembly Top")
		(33 "B.Fab" user "Ref Des/Assembly Bottom")
	)
	(footprint ""
		(layer "F.Cu")
		(at 456.051666 -380.13767 -90)
		(property "Reference" "PC6573"
			(at 4.62534 2.026666 0)
			(unlocked yes)
			(layer "F.SilkS")
			(effects
				(font
					(size 0.7874 0.5842)
					(thickness 0.1524)
				)
				(justify left)
			)
		)
		(property "Value" ""
			(at 0 0 270)
			(layer "F.Fab")
			(effects
				(font
					(size 1.27 1.27)
				)
			)
		)
		(duplicate_pad_numbers_are_jumpers no)
		(fp_line
			(start -1.988058 2.750058)
			(end 2.750058 2.750058)
			(stroke
				(width 0.1524)
				(type default)
			)
			(layer "F.SilkS")
		)
		(fp_line
			(start 2.750058 2.750058)
			(end 2.750058 0.9398)
			(stroke
				(width 0.1524)
				(type default)
			)
			(layer "F.SilkS")
		)
		(fp_line
			(start -2.750058 1.988058)
			(end -1.988058 2.750058)
			(stroke
				(width 0.1524)
				(type default)
			)
			(layer "F.SilkS")
		)
		(fp_line
			(start -2.750058 0.9398)
			(end -2.750058 1.988058)
			(stroke
				(width 0.1524)
				(type default)
			)
			(layer "F.SilkS")
		)
		(fp_line
			(start 2.750058 -0.9398)
			(end 2.750058 -2.750058)
			(stroke
				(width 0.1524)
				(type default)
			)
			(layer "F.SilkS")
		)
		(fp_line
			(start -2.750058 -1.988058)
			(end -2.750058 -0.9398)
			(stroke
				(width 0.1524)
				(type default)
			)
			(layer "F.SilkS")
		)
		(fp_line
			(start -1.988058 -2.750058)
			(end -2.750058 -1.988058)
			(stroke
				(width 0.1524)
				(type default)
			)
			(layer "F.SilkS")
		)
		(fp_line
			(start 2.750058 -2.750058)
			(end -1.988058 -2.750058)
			(stroke
				(width 0.1524)
				(type default)
			)
			(layer "F.SilkS")
		)
		(fp_line
			(start -2.750058 2.750058)
			(end 2.750058 2.750058)
			(stroke
				(width 0.1)
				(type default)
			)
			(layer "F.Fab")
		)
		(fp_line
			(start 2.750058 2.750058)
			(end 2.750058 -2.750058)
			(stroke
				(width 0.1)
				(type default)
			)
			(layer "F.Fab")
		)
		(fp_line
			(start -2.750058 -2.750058)
			(end -2.750058 2.750058)
			(stroke
				(width 0.1)
				(type default)
			)
			(layer "F.Fab")
		)
		(fp_line
			(start 2.750058 -2.750058)
			(end -2.750058 -2.750058)
			(stroke
				(width 0.1)
				(type default)
			)
			(layer "F.Fab")
		)
		(pad "1" smd rect
			(at -2.199894 0)
			(size 1.6002 3.0226)
			(layers "F.Cu" "F.Mask" "F.Paste")
			(net "P0V9_CPU0_RT_2D")
		)
		(pad "2" smd rect
			(at 2.199894 0)
			(size 1.6002 3.0226)
			(layers "F.Cu" "F.Mask" "F.Paste")
			(net "GND")
		)
	)
	(footprint ""
		(layer "F.Cu")
		(at 271.328134 -421.23868 90)
		(property "Reference" "R3907"
			(at 0 0 90)
			(layer "F.SilkS")
			(hide yes)
			(effects
				(font
					(size 1.27 1.27)
				)
			)
		)
		(property "Value" ""
			(at 0 0 90)
			(layer "F.Fab")
			(effects
				(font
					(size 1.27 1.27)
				)
			)
		)
		(duplicate_pad_numbers_are_jumpers no)
		(fp_line
			(start 0.7874 -0.4064)
			(end 0.7874 0.4064)
			(stroke
				(width 0.1524)
				(type default)
			)
			(layer "F.SilkS")
		)
		(fp_line
			(start -0.7874 -0.4064)
			(end 0.7874 -0.4064)
			(stroke
				(width 0.1524)
				(type default)
			)
			(layer "F.SilkS")
		)
		(fp_line
			(start 0.7874 0.4064)
			(end -0.7874 0.4064)
			(stroke
				(width 0.1524)
				(type default)
			)
			(layer "F.SilkS")
		)
		(fp_line
			(start -0.7874 0.4064)
			(end -0.7874 -0.4064)
			(stroke
				(width 0.1524)
				(type default)
			)
			(layer "F.SilkS")
		)
		(fp_line
			(start -0.12065 -0.305054)
			(end -0.12065 -0.2794)
			(stroke
				(width 0.1)
				(type default)
			)
			(layer "F.Fab")
		)
		(fp_line
			(start -0.67945 -0.305054)
			(end -0.12065 -0.305054)
			(stroke
				(width 0.1)
				(type default)
			)
			(layer "F.Fab")
		)
		(fp_line
			(start 0.67945 -0.3048)
			(end 0.67945 0.3048)
			(stroke
				(width 0.1)
				(type default)
			)
			(layer "F.Fab")
		)
		(fp_line
			(start 0.12065 -0.3048)
			(end 0.67945 -0.3048)
			(stroke
				(width 0.1)
				(type default)
			)
			(layer "F.Fab")
		)
		(fp_line
			(start 0.12065 -0.2794)
			(end 0.12065 -0.3048)
			(stroke
				(width 0.1)
				(type default)
			)
			(layer "F.Fab")
		)
		(fp_line
			(start -0.12065 -0.2794)
			(end 0.12065 -0.2794)
			(stroke
				(width 0.1)
				(type default)
			)
			(layer "F.Fab")
		)
		(fp_line
			(start 0.120396 0.2794)
			(end -0.12065 0.2794)
			(stroke
				(width 0.1)
				(type default)
			)
			(layer "F.Fab")
		)
		(fp_line
			(start -0.12065 0.2794)
			(end -0.12065 0.3048)
			(stroke
				(width 0.1)
				(type default)
			)
			(layer "F.Fab")
		)
		(fp_line
			(start 0.67945 0.3048)
			(end 0.120396 0.3048)
			(stroke
				(width 0.1)
				(type default)
			)
			(layer "F.Fab")
		)
		(fp_line
			(start 0.120396 0.3048)
			(end 0.120396 0.2794)
			(stroke
				(width 0.1)
				(type default)
			)
			(layer "F.Fab")
		)
		(fp_line
			(start -0.12065 0.3048)
			(end -0.67945 0.3048)
			(stroke
				(width 0.1)
				(type default)
			)
			(layer "F.Fab")
		)
		(fp_line
			(start -0.67945 0.3048)
			(end -0.67945 -0.305054)
			(stroke
				(width 0.1)
				(type default)
			)
			(layer "F.Fab")
		)
		(pad "1" smd circle
			(at -0.40005 0 90)
			(size 0 0)
			(layers "F.Cu" "F.Mask" "F.Paste")
			(net "PDB_PRSNT_R_N")
		)
		(pad "2" smd circle
			(at 0.40005 0 90)
			(size 0 0)
			(layers "F.Cu" "F.Mask" "F.Paste")
			(net "GND")
		)
	)
	(footprint ""
		(layer "F.Cu")
		(at 327.951084 -349.43161 180)
		(property "Reference" "PC101"
			(at -0.199644 -2.938272 0)
			(unlocked yes)
			(layer "F.SilkS")
			(effects
				(font
					(size 0.7874 0.5842)
					(thickness 0.1524)
				)
				(justify left)
			)
		)
		(property "Value" ""
			(at 0 0 180)
			(layer "F.Fab")
			(effects
				(font
					(size 1.27 1.27)
				)
			)
		)
		(duplicate_pad_numbers_are_jumpers no)
		(fp_line
			(start -3.400044 1.249934)
			(end 3.400044 1.249934)
			(stroke
				(width 0.1524)
				(type default)
			)
			(layer "F.SilkS")
		)
		(fp_circle
			(center 0 1.249934)
			(end -3.400044 1.249934)
			(stroke
				(width 0.1524)
				(type default)
			)
			(fill no)
			(layer "F.SilkS")
		)
		(fp_poly
			(pts
				(arc
					(start 3.400044 1.249934)
					(mid 0 4.649978)
					(end -3.400044 1.249934)
				)
			)
			(stroke
				(width 0)
				(type default)
			)
			(fill yes)
			(layer "F.SilkS")
		)
		(fp_circle
			(center 0 1.249934)
			(end -3.400044 1.249934)
			(stroke
				(width 0.1)
				(type default)
			)
			(fill no)
			(layer "F.Fab")
		)
		(pad "1" thru_hole rect
			(at 0 0 180)
			(size 1.524 1.524)
			(drill 1.016)
			(layers "*.Cu" "*.Mask")
			(remove_unused_layers no)
			(net "SW_P12V_AUX_PVDDCR_CPU1_P0_FLT")
			(clearance 0)
			(padstack
				(mode front_inner_back)
				(layer "Inner"
					(shape circle)
					(size 1.524 1.524)
					(clearance 0)
				)
				(layer "B.Cu"
					(shape rect)
					(size 1.524 1.524)
					(clearance 0)
				)
			)
		)
		(pad "2" thru_hole circle
			(at 0 2.500122 180)
			(size 1.524 1.524)
			(drill 1.016)
			(layers "*.Cu" "*.Mask")
			(remove_unused_layers no)
			(net "GND")
			(clearance 0)
		)
	)
)
